# T6G (Grand Teton) — schematic netlist excerpt (pin names and nets, part order shuffled) for the footprints in the layout excerpt that follows; sources: Cadence DE-HDL packaged netlist, KiCad conversion of 04192023_DAF0TMB3IC0_F0TG_MB_C_brd_V02_OCP.brd

C6505  Q_CAP_DIFFBUS  DIFF BUS_0.22UF 6.3V 20% X6S  pkg C0201  page 275 : \1\ = P5E_CPU0_P0_TX_BUF_C_DP<2> ; \2\ = P5E_CPU0_P0_TX_BUF_DP<2>
R4493  Q_RES  1 1% CHIP  pkg 0603LF  page 182 : A = P3V3_9ZXL045_P0 ; B = P3V3_9ZXL045_P0_VDDA
R1266  Q_RES  200 1% CHIP  pkg 0402LF  page 85 : A = P3V3_AUX ; B = BMC_FPGA_LED1_R_N

(kicad_pcb
	(version 20260206)
	(generator "pcbnew")
	(generator_version "10.0")
	(general
		(thickness 1.6)
		(legacy_teardrops no)
	)
	(paper "A4")
	(title_block
		(title "04192023_DAF0TMB3IC0_F0TG_MB_C_brd_V02_OCP.brd")
		(comment 1 "Grand Teton / footprints 1389-1391 of 8354")
	)
	(layers
		(0 "F.Cu" signal "TOP")
		(4 "In1.Cu" signal "GND")
		(6 "In2.Cu" signal "IN1")
		(8 "In3.Cu" signal "GND1")
		(10 "In4.Cu" signal "IN2")
		(12 "In5.Cu" signal "GND2")
		(14 "In6.Cu" signal "IN3")
		(16 "In7.Cu" signal "GND3")
		(18 "In8.Cu" signal "VCC")
		(20 "In9.Cu" signal "VCC1")
		(22 "In10.Cu" signal "GND4")
		(24 "In11.Cu" signal "IN4")
		(26 "In12.Cu" signal "GND5")
		(28 "In13.Cu" signal "IN5")
		(30 "In14.Cu" signal "GND6")
		(32 "In15.Cu" signal "IN6")
		(34 "In16.Cu" signal "GND7")
		(2 "B.Cu" signal "BOTTOM")
		(9 "F.Adhes" user "F.Adhesive")
		(11 "B.Adhes" user "B.Adhesive")
		(13 "F.Paste" user "Package Geometry/Pastemask Top")
		(15 "B.Paste" user "Package Geometry/Pastemask Bottom")
		(5 "F.SilkS" user "Ref Des/Silkscreen Top")
		(7 "B.SilkS" user "Ref Des/Silkscreen Bottom")
		(1 "F.Mask" user "Board Geometry/Soldermask Top")
		(3 "B.Mask" user "Board Geometry/Soldermask Bottom")
		(17 "Dwgs.User" user "User.Drawings")
		(19 "Cmts.User" user "User.Comments")
		(21 "Eco1.User" user "User.Eco1")
		(23 "Eco2.User" user "User.Eco2")
		(25 "Edge.Cuts" user "Board Geometry/Outline")
		(27 "Margin" user)
		(31 "F.CrtYd" user "Package Geometry/Place Bound Top")
		(29 "B.CrtYd" user "Package Geometry/Place Bound Bottom")
		(35 "F.Fab" user "Ref Des/Assembly Top")
		(33 "B.Fab" user "Ref Des/Assembly Bottom")
	)
	(footprint ""
		(layer "F.Cu")
		(at 310.809386 -416.899344 -90)
		(property "Reference" "C6505"
			(at 0 0 270)
			(layer "F.SilkS")
			(hide yes)
			(effects
				(font
					(size 1.27 1.27)
				)
			)
		)
		(property "Value" ""
			(at 0 0 270)
			(layer "F.Fab")
			(effects
				(font
					(size 1.27 1.27)
				)
			)
		)
		(duplicate_pad_numbers_are_jumpers no)
		(fp_line
			(start -0.299974 0.150114)
			(end -0.299974 -0.150114)
			(stroke
				(width 0.1)
				(type default)
			)
			(layer "F.Fab")
		)
		(fp_line
			(start 0.299974 0.150114)
			(end -0.299974 0.150114)
			(stroke
				(width 0.1)
				(type default)
			)
			(layer "F.Fab")
		)
		(fp_line
			(start -0.299974 -0.150114)
			(end 0.299974 -0.150114)
			(stroke
				(width 0.1)
				(type default)
			)
			(layer "F.Fab")
		)
		(fp_line
			(start 0.299974 -0.150114)
			(end 0.299974 0.150114)
			(stroke
				(width 0.1)
				(type default)
			)
			(layer "F.Fab")
		)
		(pad "1" smd rect
			(at -0.2667 0 270)
			(size 0.3048 0.381)
			(layers "F.Cu" "F.Mask" "F.Paste")
			(net "P5E_CPU0_P0_TX_BUF_C_DP<2>")
		)
		(pad "2" smd rect
			(at 0.2667 0 270)
			(size 0.3048 0.381)
			(layers "F.Cu" "F.Mask" "F.Paste")
			(net "P5E_CPU0_P0_TX_BUF_DP<2>")
		)
	)
	(footprint ""
		(layer "F.Cu")
		(at 283.265118 -426.20565 -90)
		(property "Reference" "R4493"
			(at 0 0 270)
			(layer "F.SilkS")
			(hide yes)
			(effects
				(font
					(size 1.27 1.27)
				)
			)
		)
		(property "Value" ""
			(at 0 0 270)
			(layer "F.Fab")
			(effects
				(font
					(size 1.27 1.27)
				)
			)
		)
		(duplicate_pad_numbers_are_jumpers no)
		(fp_line
			(start -1.2954 0.5842)
			(end -1.2954 -0.5842)
			(stroke
				(width 0.1524)
				(type default)
			)
			(layer "F.SilkS")
		)
		(fp_line
			(start 1.2954 0.5842)
			(end -1.2954 0.5842)
			(stroke
				(width 0.1524)
				(type default)
			)
			(layer "F.SilkS")
		)
		(fp_line
			(start -1.2954 -0.5842)
			(end 1.2954 -0.5842)
			(stroke
				(width 0.1524)
				(type default)
			)
			(layer "F.SilkS")
		)
		(fp_line
			(start 1.2954 -0.5842)
			(end 1.2954 0.5842)
			(stroke
				(width 0.1524)
				(type default)
			)
			(layer "F.SilkS")
		)
		(fp_line
			(start -0.8636 0.4572)
			(end -0.8636 0.4318)
			(stroke
				(width 0.1)
				(type default)
			)
			(layer "F.Fab")
		)
		(fp_line
			(start 0.8636 0.4572)
			(end -0.8636 0.4572)
			(stroke
				(width 0.1)
				(type default)
			)
			(layer "F.Fab")
		)
		(fp_line
			(start -0.8636 0.4318)
			(end -0.8636 0.4064)
			(stroke
				(width 0.1)
				(type default)
			)
			(layer "F.Fab")
		)
		(fp_line
			(start -1.1938 0.4064)
			(end -1.1938 -0.406654)
			(stroke
				(width 0.1)
				(type default)
			)
			(layer "F.Fab")
		)
		(fp_line
			(start -0.8636 0.4064)
			(end -1.1938 0.4064)
			(stroke
				(width 0.1)
				(type default)
			)
			(layer "F.Fab")
		)
		(fp_line
			(start 0.8636 0.4064)
			(end 0.8636 0.4572)
			(stroke
				(width 0.1)
				(type default)
			)
			(layer "F.Fab")
		)
		(fp_line
			(start 1.1938 0.4064)
			(end 0.8636 0.4064)
			(stroke
				(width 0.1)
				(type default)
			)
			(layer "F.Fab")
		)
		(fp_line
			(start -1.1938 -0.406654)
			(end -0.8636 -0.406654)
			(stroke
				(width 0.1)
				(type default)
			)
			(layer "F.Fab")
		)
		(fp_line
			(start -0.8636 -0.406654)
			(end -0.8636 -0.4572)
			(stroke
				(width 0.1)
				(type default)
			)
			(layer "F.Fab")
		)
		(fp_line
			(start 0.8636 -0.406654)
			(end 1.1938 -0.406654)
			(stroke
				(width 0.1)
				(type default)
			)
			(layer "F.Fab")
		)
		(fp_line
			(start 1.1938 -0.406654)
			(end 1.1938 0.4064)
			(stroke
				(width 0.1)
				(type default)
			)
			(layer "F.Fab")
		)
		(fp_line
			(start -0.8636 -0.4572)
			(end 0.8636 -0.4572)
			(stroke
				(width 0.1)
				(type default)
			)
			(layer "F.Fab")
		)
		(fp_line
			(start 0.8636 -0.4572)
			(end 0.8636 -0.406654)
			(stroke
				(width 0.1)
				(type default)
			)
			(layer "F.Fab")
		)
		(pad "1" smd rect
			(at -0.7366 0 180)
			(size 0.7112 0.8128)
			(layers "F.Cu" "F.Mask" "F.Paste")
			(net "P3V3_9ZXL045_P0")
		)
		(pad "2" smd rect
			(at 0.7366 0 180)
			(size 0.7112 0.8128)
			(layers "F.Cu" "F.Mask" "F.Paste")
			(net "P3V3_9ZXL045_P0_VDDA")
		)
	)
	(footprint ""
		(layer "F.Cu")
		(at 332.25994 -15.979394 -90)
		(property "Reference" "R1266"
			(at 0 0 270)
			(layer "F.SilkS")
			(hide yes)
			(effects
				(font
					(size 1.27 1.27)
				)
			)
		)
		(property "Value" ""
			(at 0 0 270)
			(layer "F.Fab")
			(effects
				(font
					(size 1.27 1.27)
				)
			)
		)
		(duplicate_pad_numbers_are_jumpers no)
		(fp_line
			(start -0.7874 0.4064)
			(end -0.7874 -0.4064)
			(stroke
				(width 0.1524)
				(type default)
			)
			(layer "F.SilkS")
		)
		(fp_line
			(start 0.7874 0.4064)
			(end -0.7874 0.4064)
			(stroke
				(width 0.1524)
				(type default)
			)
			(layer "F.SilkS")
		)
		(fp_line
			(start -0.7874 -0.4064)
			(end 0.7874 -0.4064)
			(stroke
				(width 0.1524)
				(type default)
			)
			(layer "F.SilkS")
		)
		(fp_line
			(start 0.7874 -0.4064)
			(end 0.7874 0.4064)
			(stroke
				(width 0.1524)
				(type default)
			)
			(layer "F.SilkS")
		)
		(fp_line
			(start -0.67945 0.3048)
			(end -0.67945 -0.305054)
			(stroke
				(width 0.1)
				(type default)
			)
			(layer "F.Fab")
		)
		(fp_line
			(start -0.12065 0.3048)
			(end -0.67945 0.3048)
			(stroke
				(width 0.1)
				(type default)
			)
			(layer "F.Fab")
		)
		(fp_line
			(start 0.120396 0.3048)
			(end 0.120396 0.2794)
			(stroke
				(width 0.1)
				(type default)
			)
			(layer "F.Fab")
		)
		(fp_line
			(start 0.67945 0.3048)
			(end 0.120396 0.3048)
			(stroke
				(width 0.1)
				(type default)
			)
			(layer "F.Fab")
		)
		(fp_line
			(start -0.12065 0.2794)
			(end -0.12065 0.3048)
			(stroke
				(width 0.1)
				(type default)
			)
			(layer "F.Fab")
		)
		(fp_line
			(start 0.120396 0.2794)
			(end -0.12065 0.2794)
			(stroke
				(width 0.1)
				(type default)
			)
			(layer "F.Fab")
		)
		(fp_line
			(start -0.12065 -0.2794)
			(end 0.12065 -0.2794)
			(stroke
				(width 0.1)
				(type default)
			)
			(layer "F.Fab")
		)
		(fp_line
			(start 0.12065 -0.2794)
			(end 0.12065 -0.3048)
			(stroke
				(width 0.1)
				(type default)
			)
			(layer "F.Fab")
		)
		(fp_line
			(start 0.12065 -0.3048)
			(end 0.67945 -0.3048)
			(stroke
				(width 0.1)
				(type default)
			)
			(layer "F.Fab")
		)
		(fp_line
			(start 0.67945 -0.3048)
			(end 0.67945 0.3048)
			(stroke
				(width 0.1)
				(type default)
			)
			(layer "F.Fab")
		)
		(fp_line
			(start -0.67945 -0.305054)
			(end -0.12065 -0.305054)
			(stroke
				(width 0.1)
				(type default)
			)
			(layer "F.Fab")
		)
		(fp_line
			(start -0.12065 -0.305054)
			(end -0.12065 -0.2794)
			(stroke
				(width 0.1)
				(type default)
			)
			(layer "F.Fab")
		)
		(pad "1" smd circle
			(at -0.40005 0 270)
			(size 0 0)
			(layers "F.Cu" "F.Mask" "F.Paste")
			(net "P3V3_AUX")
		)
		(pad "2" smd circle
			(at 0.40005 0 270)
			(size 0 0)
			(layers "F.Cu" "F.Mask" "F.Paste")
			(net "BMC_FPGA_LED1_R_N")
		)
	)
)
